(kicad_pcb
	(version 20241229)
	(generator "pcbnew")
	(generator_version "9.0")
	(general
		(thickness 1.6296)
		(legacy_teardrops no)
	)
	(paper "A3")
	(title_block
		(title "Thunderbolt to 10GbE adapter")
		(date "2026-04-21")
		(rev "1.1.0")
		(company "Antmicro Ltd")
		(comment 1 "www.antmicro.com")
		(comment 9 "footprints 682-685 of 703")
	)
	(layers
		(0 "F.Cu" signal)
		(4 "In1.Cu" signal)
		(6 "In2.Cu" signal)
		(8 "In3.Cu" signal)
		(10 "In4.Cu" signal)
		(12 "In5.Cu" signal)
		(14 "In6.Cu" signal)
		(2 "B.Cu" signal)
		(9 "F.Adhes" user "F.Adhesive")
		(11 "B.Adhes" user "B.Adhesive")
		(13 "F.Paste" user)
		(15 "B.Paste" user)
		(5 "F.SilkS" user "F.Silkscreen")
		(7 "B.SilkS" user "B.Silkscreen")
		(1 "F.Mask" user)
		(3 "B.Mask" user)
		(17 "Dwgs.User" user "User.Drawings")
		(19 "Cmts.User" user "User.Comments")
		(21 "Eco1.User" user "User.Eco1")
		(23 "Eco2.User" user "User.Eco2")
		(25 "Edge.Cuts" user)
		(27 "Margin" user)
		(31 "F.CrtYd" user "F.Courtyard")
		(29 "B.CrtYd" user "B.Courtyard")
		(35 "F.Fab" user)
		(33 "B.Fab" user)
	)
	(footprint "antmicro-footprints:C_0402_1005Metric"
		(layer "B.Cu")
		(at 147.531866 71.535117)
		(descr "Capacitor SMD 0402")
		(tags "capacitor SMD 0402")
		(property "Reference" "C214"
			(at 19.068134 9.464883 180)
			(layer "B.SilkS")
			(effects
				(font
					(size 0.7 0.7)
					(thickness 0.15)
				)
				(justify mirror)
			)
		)
		(property "Value" "C_100n_0402"
			(at -1.022927 -2.155213 180)
			(layer "B.Fab")
			(effects
				(font
					(size 0.7 0.7)
					(thickness 0.15)
				)
				(justify left bottom mirror)
			)
		)
		(property "Datasheet" "https://www.murata.com/products/productdetail?partno=GRM155R61H104KE14%23"
			(at 0 0 180)
			(layer "B.Fab")
			(hide yes)
			(effects
				(font
					(size 1.27 1.27)
					(thickness 0.15)
				)
				(justify mirror)
			)
		)
		(property "Description" "SMD Multilayer Ceramic Capacitor, 0.1 µF, 50 V, 0402 [1005 Metric], ± 10%, X5R, GRM Series"
			(at 0 0 180)
			(layer "B.Fab")
			(hide yes)
			(effects
				(font
					(size 1.27 1.27)
					(thickness 0.15)
				)
				(justify mirror)
			)
		)
		(property "MPN" "GRM155R61H104KE14D"
			(at 0 0 0)
			(unlocked yes)
			(layer "B.Fab")
			(hide yes)
			(effects
				(font
					(size 1 1)
					(thickness 0.15)
				)
				(justify mirror)
			)
		)
		(property "Val" "100n"
			(at 0 0 0)
			(unlocked yes)
			(layer "B.Fab")
			(hide yes)
			(effects
				(font
					(size 1 1)
					(thickness 0.15)
				)
				(justify mirror)
			)
		)
		(property "Voltage" "50V"
			(at 0 0 0)
			(unlocked yes)
			(layer "B.Fab")
			(hide yes)
			(effects
				(font
					(size 1 1)
					(thickness 0.15)
				)
				(justify mirror)
			)
		)
		(property "Dielectric" "X5R"
			(at 0 0 0)
			(unlocked yes)
			(layer "B.Fab")
			(hide yes)
			(effects
				(font
					(size 1 1)
					(thickness 0.15)
				)
				(justify mirror)
			)
		)
		(property "Manufacturer" "Murata"
			(at 0 0 0)
			(unlocked yes)
			(layer "B.Fab")
			(hide yes)
			(effects
				(font
					(size 1 1)
					(thickness 0.15)
				)
				(justify mirror)
			)
		)
		(property "License" "Apache-2.0"
			(at 0 0 0)
			(unlocked yes)
			(layer "B.Fab")
			(hide yes)
			(effects
				(font
					(size 1 1)
					(thickness 0.15)
				)
				(justify mirror)
			)
		)
		(property "Author" "Antmicro"
			(at 0 0 0)
			(unlocked yes)
			(layer "B.Fab")
			(hide yes)
			(effects
				(font
					(size 1 1)
					(thickness 0.15)
				)
				(justify mirror)
			)
		)
		(sheetname "/X710-AT2 power/")
		(sheetfile "x710-at2-power.kicad_sch")
		(attr smd)
		(fp_rect
			(start -0.925 0.47)
			(end 0.925 -0.47)
			(stroke
				(width 0.05)
				(type default)
			)
			(fill no)
			(layer "B.CrtYd")
		)
		(fp_line
			(start -0.494 -0.248)
			(end -0.494 0.25)
			(stroke
				(width 0.15)
				(type solid)
			)
			(layer "B.Fab")
		)
		(fp_line
			(start -0.494 0.25)
			(end 0.504 0.25)
			(stroke
				(width 0.15)
				(type solid)
			)
			(layer "B.Fab")
		)
		(fp_line
			(start 0.504 -0.248)
			(end -0.494 -0.248)
			(stroke
				(width 0.15)
				(type solid)
			)
			(layer "B.Fab")
		)
		(fp_line
			(start 0.504 0.25)
			(end 0.504 -0.248)
			(stroke
				(width 0.15)
				(type solid)
			)
			(layer "B.Fab")
		)
		(fp_text user "License: Apache-2.0"
			(at -0.939 -5.799 180)
			(layer "B.Fab")
			(effects
				(font
					(size 0.7 0.7)
					(thickness 0.15)
				)
				(justify left bottom mirror)
			)
		)
		(fp_text user "Author: Antmicro"
			(at -0.939 -3.399 180)
			(layer "B.Fab")
			(effects
				(font
					(size 0.7 0.7)
					(thickness 0.15)
				)
				(justify left bottom mirror)
			)
		)
		(fp_text user "${REFERENCE}"
			(at -0.939 -4.599 180)
			(layer "B.Fab")
			(effects
				(font
					(size 0.7 0.7)
					(thickness 0.15)
				)
				(justify left bottom mirror)
			)
		)
		(pad "1" smd roundrect
			(at -0.48 0)
			(size 0.59 0.64)
			(layers "B.Cu" "B.Mask" "B.Paste")
			(roundrect_rratio 0.25)
			(net 23 "GND")
			(pintype "passive")
		)
		(pad "2" smd roundrect
			(at 0.48 0)
			(size 0.59 0.64)
			(layers "B.Cu" "B.Mask" "B.Paste")
			(roundrect_rratio 0.25)
			(net 7 "+3V3")
			(pintype "passive")
		)
	)
	(footprint "antmicro-footprints:C_0402_1005Metric"
		(layer "B.Cu")
		(at 145 136)
		(descr "Capacitor SMD 0402")
		(tags "capacitor SMD 0402")
		(property "Reference" "C296"
			(at 1 -0.5 180)
			(layer "B.SilkS")
			(effects
				(font
					(size 0.7 0.7)
					(thickness 0.15)
				)
				(justify left bottom mirror)
			)
		)
		(property "Value" "C_1u_25V_0402"
			(at -1.022927 -2.155213 180)
			(layer "B.Fab")
			(effects
				(font
					(size 0.7 0.7)
					(thickness 0.15)
				)
				(justify left bottom mirror)
			)
		)
		(property "Datasheet" "https://www.murata.com/products/productdetail?partno=GRM155R61E105KE11%23"
			(at 0 0 180)
			(layer "B.Fab")
			(hide yes)
			(effects
				(font
					(size 1.27 1.27)
					(thickness 0.15)
				)
				(justify mirror)
			)
		)
		(property "Description" "SMD Multilayer Ceramic Capacitor, 1 µF, 25 V, 0402 [1005 Metric], ± 10%, X5R, GRM Series"
			(at 0 0 180)
			(layer "B.Fab")
			(hide yes)
			(effects
				(font
					(size 1.27 1.27)
					(thickness 0.15)
				)
				(justify mirror)
			)
		)
		(property "MPN" "GRM155R61E105KE11J"
			(at 0 0 0)
			(unlocked yes)
			(layer "B.Fab")
			(hide yes)
			(effects
				(font
					(size 1 1)
					(thickness 0.15)
				)
				(justify mirror)
			)
		)
		(property "Manufacturer" "Murata"
			(at 0 0 0)
			(unlocked yes)
			(layer "B.Fab")
			(hide yes)
			(effects
				(font
					(size 1 1)
					(thickness 0.15)
				)
				(justify mirror)
			)
		)
		(property "License" "Apache-2.0"
			(at 0 0 0)
			(unlocked yes)
			(layer "B.Fab")
			(hide yes)
			(effects
				(font
					(size 1 1)
					(thickness 0.15)
				)
				(justify mirror)
			)
		)
		(property "Author" "Antmicro"
			(at 0 0 0)
			(unlocked yes)
			(layer "B.Fab")
			(hide yes)
			(effects
				(font
					(size 1 1)
					(thickness 0.15)
				)
				(justify mirror)
			)
		)
		(property "Val" "1u"
			(at 0 0 0)
			(unlocked yes)
			(layer "B.Fab")
			(hide yes)
			(effects
				(font
					(size 1 1)
					(thickness 0.15)
				)
				(justify mirror)
			)
		)
		(property "Voltage" "25V"
			(at 0 0 0)
			(unlocked yes)
			(layer "B.Fab")
			(hide yes)
			(effects
				(font
					(size 1 1)
					(thickness 0.15)
				)
				(justify mirror)
			)
		)
		(property "Dielectric" "X5R"
			(at 0 0 0)
			(unlocked yes)
			(layer "B.Fab")
			(hide yes)
			(effects
				(font
					(size 1 1)
					(thickness 0.15)
				)
				(justify mirror)
			)
		)
		(sheetname "/2xRJ45/")
		(sheetfile "2xrj45.kicad_sch")
		(attr smd)
		(fp_rect
			(start -0.925 0.47)
			(end 0.925 -0.47)
			(stroke
				(width 0.05)
				(type default)
			)
			(fill no)
			(layer "B.CrtYd")
		)
		(fp_line
			(start -0.494 -0.248)
			(end -0.494 0.25)
			(stroke
				(width 0.15)
				(type solid)
			)
			(layer "B.Fab")
		)
		(fp_line
			(start -0.494 0.25)
			(end 0.504 0.25)
			(stroke
				(width 0.15)
				(type solid)
			)
			(layer "B.Fab")
		)
		(fp_line
			(start 0.504 -0.248)
			(end -0.494 -0.248)
			(stroke
				(width 0.15)
				(type solid)
			)
			(layer "B.Fab")
		)
		(fp_line
			(start 0.504 0.25)
			(end 0.504 -0.248)
			(stroke
				(width 0.15)
				(type solid)
			)
			(layer "B.Fab")
		)
		(fp_text user "Author: Antmicro"
			(at -0.939 -3.399 180)
			(layer "B.Fab")
			(effects
				(font
					(size 0.7 0.7)
					(thickness 0.15)
				)
				(justify left bottom mirror)
			)
		)
		(fp_text user "License: Apache-2.0"
			(at -0.939 -5.799 180)
			(layer "B.Fab")
			(effects
				(font
					(size 0.7 0.7)
					(thickness 0.15)
				)
				(justify left bottom mirror)
			)
		)
		(fp_text user "${REFERENCE}"
			(at -0.939 -4.599 180)
			(layer "B.Fab")
			(effects
				(font
					(size 0.7 0.7)
					(thickness 0.15)
				)
				(justify left bottom mirror)
			)
		)
		(pad "1" smd roundrect
			(at -0.48 0)
			(size 0.59 0.64)
			(layers "B.Cu" "B.Mask" "B.Paste")
			(roundrect_rratio 0.25)
			(net 23 "GND")
			(pintype "passive")
		)
		(pad "2" smd roundrect
			(at 0.48 0)
			(size 0.59 0.64)
			(layers "B.Cu" "B.Mask" "B.Paste")
			(roundrect_rratio 0.25)
			(net 133 "/2xRJ45/P0_CT")
			(pintype "passive")
		)
	)
	(footprint "antmicro-footprints:C_0402_1005Metric"
		(layer "B.Cu")
		(at 125.625 126.9 90)
		(descr "Capacitor SMD 0402")
		(tags "capacitor SMD 0402")
		(property "Reference" "C85"
			(at 7.700002 21.900002 270)
			(layer "B.SilkS")
			(effects
				(font
					(size 0.7 0.7)
					(thickness 0.15)
				)
				(justify mirror)
			)
		)
		(property "Value" "C_1u_0402"
			(at -1.022927 -2.155213 270)
			(layer "B.Fab")
			(effects
				(font
					(size 0.7 0.7)
					(thickness 0.15)
				)
				(justify left bottom mirror)
			)
		)
		(property "Datasheet" "https://product.tdk.com/en/search/capacitor/ceramic/mlcc/info?part_no=C1005X6S1A105K050BC"
			(at 0 0 270)
			(layer "B.Fab")
			(hide yes)
			(effects
				(font
					(size 1.27 1.27)
					(thickness 0.15)
				)
				(justify mirror)
			)
		)
		(property "Description" "SMD Multilayer Ceramic Capacitor, 1 µF, 10 V, 0402 [1005 Metric], ± 10%, X6S, C"
			(at 0 0 270)
			(layer "B.Fab")
			(hide yes)
			(effects
				(font
					(size 1.27 1.27)
					(thickness 0.15)
				)
				(justify mirror)
			)
		)
		(property "MPN" "C1005X6S1A105K050BC"
			(at 0 0 90)
			(unlocked yes)
			(layer "B.Fab")
			(hide yes)
			(effects
				(font
					(size 1 1)
					(thickness 0.15)
				)
				(justify mirror)
			)
		)
		(property "Manufacturer" "TDK"
			(at 0 0 90)
			(unlocked yes)
			(layer "B.Fab")
			(hide yes)
			(effects
				(font
					(size 1 1)
					(thickness 0.15)
				)
				(justify mirror)
			)
		)
		(property "License" "Apache-2.0"
			(at 0 0 90)
			(unlocked yes)
			(layer "B.Fab")
			(hide yes)
			(effects
				(font
					(size 1 1)
					(thickness 0.15)
				)
				(justify mirror)
			)
		)
		(property "Val" "1u"
			(at 0 0 90)
			(unlocked yes)
			(layer "B.Fab")
			(hide yes)
			(effects
				(font
					(size 1 1)
					(thickness 0.15)
				)
				(justify mirror)
			)
		)
		(property "Voltage" ""
			(at 0 0 90)
			(unlocked yes)
			(layer "B.Fab")
			(hide yes)
			(effects
				(font
					(size 1 1)
					(thickness 0.15)
				)
				(justify mirror)
			)
		)
		(property "Dielectric" ""
			(at 0 0 90)
			(unlocked yes)
			(layer "B.Fab")
			(hide yes)
			(effects
				(font
					(size 1 1)
					(thickness 0.15)
				)
				(justify mirror)
			)
		)
		(property "Author" "Antmicro"
			(at 0 0 90)
			(unlocked yes)
			(layer "B.Fab")
			(hide yes)
			(effects
				(font
					(size 1 1)
					(thickness 0.15)
				)
				(justify mirror)
			)
		)
		(sheetname "/TB Controller - Power/")
		(sheetfile "tb-power.kicad_sch")
		(attr smd)
		(fp_rect
			(start -0.925 0.47)
			(end 0.925 -0.47)
			(stroke
				(width 0.05)
				(type default)
			)
			(fill no)
			(layer "B.CrtYd")
		)
		(fp_line
			(start 0.504 -0.248)
			(end -0.494 -0.248)
			(stroke
				(width 0.15)
				(type solid)
			)
			(layer "B.Fab")
		)
		(fp_line
			(start -0.494 -0.248)
			(end -0.494 0.25)
			(stroke
				(width 0.15)
				(type solid)
			)
			(layer "B.Fab")
		)
		(fp_line
			(start 0.504 0.25)
			(end 0.504 -0.248)
			(stroke
				(width 0.15)
				(type solid)
			)
			(layer "B.Fab")
		)
		(fp_line
			(start -0.494 0.25)
			(end 0.504 0.25)
			(stroke
				(width 0.15)
				(type solid)
			)
			(layer "B.Fab")
		)
		(fp_text user "License: Apache-2.0"
			(at -0.939 -5.799 270)
			(layer "B.Fab")
			(effects
				(font
					(size 0.7 0.7)
					(thickness 0.15)
				)
				(justify left bottom mirror)
			)
		)
		(fp_text user "${REFERENCE}"
			(at -0.939 -4.599 270)
			(layer "B.Fab")
			(effects
				(font
					(size 0.7 0.7)
					(thickness 0.15)
				)
				(justify left bottom mirror)
			)
		)
		(fp_text user "Author: Antmicro"
			(at -0.939 -3.399 270)
			(layer "B.Fab")
			(effects
				(font
					(size 0.7 0.7)
					(thickness 0.15)
				)
				(justify left bottom mirror)
			)
		)
		(pad "1" smd roundrect
			(at -0.48 0 90)
			(size 0.59 0.64)
			(layers "B.Cu" "B.Mask" "B.Paste")
			(roundrect_rratio 0.25)
			(net 23 "GND")
			(pintype "passive")
		)
		(pad "2" smd roundrect
			(at 0.48 0 90)
			(size 0.59 0.64)
			(layers "B.Cu" "B.Mask" "B.Paste")
			(roundrect_rratio 0.25)
			(net 180 "Net-(U4A-VCC0P9_LVR_SENSE)")
			(pintype "passive")
		)
	)
	(footprint "antmicro-footprints:R_0402_1005Metric"
		(layer "B.Cu")
		(at 154.481865 74.785117 -90)
		(descr "Resistor SMD 0402")
		(tags "resistor SMD 0402")
		(property "Reference" "R203"
			(at 8.014883 -21.618136 90)
			(layer "B.SilkS")
			(effects
				(font
					(size 0.7 0.7)
					(thickness 0.15)
				)
				(justify mirror)
			)
		)
		(property "Value" "R_100R_0402"
			(at -1.011843 -1.772047 90)
			(layer "B.Fab")
			(effects
				(font
					(size 0.7 0.7)
					(thickness 0.15)
				)
				(justify left bottom mirror)
			)
		)
		(property "Datasheet" "https://www.bourns.com/docs/product-datasheets/cr.pdf"
			(at 0 0 90)
			(layer "B.Fab")
			(hide yes)
			(effects
				(font
					(size 1.27 1.27)
					(thickness 0.15)
				)
				(justify mirror)
			)
		)
		(property "Description" "SMD Chip Resistor, 100 ohm, ± 1%, 62.5 mW, 0402 [1005 Metric], Thick Film, General Purpose"
			(at 0 0 90)
			(layer "B.Fab")
			(hide yes)
			(effects
				(font
					(size 1.27 1.27)
					(thickness 0.15)
				)
				(justify mirror)
			)
		)
		(property "MPN" "CR0402-FX-1000GLF"
			(at 0 0 270)
			(unlocked yes)
			(layer "B.Fab")
			(hide yes)
			(effects
				(font
					(size 1 1)
					(thickness 0.15)
				)
				(justify mirror)
			)
		)
		(property "Manufacturer" "Bourns"
			(at 0 0 270)
			(unlocked yes)
			(layer "B.Fab")
			(hide yes)
			(effects
				(font
					(size 1 1)
					(thickness 0.15)
				)
				(justify mirror)
			)
		)
		(property "License" "Apache-2.0"
			(at 0 0 270)
			(unlocked yes)
			(layer "B.Fab")
			(hide yes)
			(effects
				(font
					(size 1 1)
					(thickness 0.15)
				)
				(justify mirror)
			)
		)
		(property "Author" "Antmicro"
			(at 0 0 270)
			(unlocked yes)
			(layer "B.Fab")
			(hide yes)
			(effects
				(font
					(size 1 1)
					(thickness 0.15)
				)
				(justify mirror)
			)
		)
		(property "Val" "100R"
			(at 0 0 270)
			(unlocked yes)
			(layer "B.Fab")
			(hide yes)
			(effects
				(font
					(size 1 1)
					(thickness 0.15)
				)
				(justify mirror)
			)
		)
		(property "Tolerance" "1%"
			(at 0 0 270)
			(unlocked yes)
			(layer "B.Fab")
			(hide yes)
			(effects
				(font
					(size 1 1)
					(thickness 0.15)
				)
				(justify mirror)
			)
		)
		(sheetname "/X710-AT2 10GbE/")
		(sheetfile "x710-at2-10gbe.kicad_sch")
		(attr smd dnp)
		(fp_rect
			(start -0.925 0.47)
			(end 0.925 -0.47)
			(stroke
				(width 0.05)
				(type default)
			)
			(fill no)
			(layer "B.CrtYd")
		)
		(fp_rect
			(start -0.5 0.25)
			(end 0.5 -0.25)
			(stroke
				(width 0.15)
				(type solid)
			)
			(fill no)
			(layer "B.Fab")
		)
		(fp_text user "License: Apache-2.0"
			(at -0.95 -5.169 90)
			(layer "B.Fab")
			(effects
				(font
					(size 0.7 0.7)
					(thickness 0.15)
				)
				(justify left bottom mirror)
			)
		)
		(fp_text user "${REFERENCE}"
			(at -0.95 -3.168 90)
			(layer "B.Fab")
			(effects
				(font
					(size 0.7 0.7)
					(thickness 0.15)
				)
				(justify left bottom mirror)
			)
		)
		(fp_text user "Author: Antmicro"
			(at -0.95 -4.169 90)
			(layer "B.Fab")
			(effects
				(font
					(size 0.7 0.7)
					(thickness 0.15)
				)
				(justify left bottom mirror)
			)
		)
		(pad "1" smd roundrect
			(at -0.48 0 270)
			(size 0.59 0.64)
			(layers "B.Cu" "B.Mask" "B.Paste")
			(roundrect_rratio 0.25)
			(net 23 "GND")
			(pintype "passive")
		)
		(pad "2" smd roundrect
			(at 0.48 0 270)
			(size 0.59 0.64)
			(layers "B.Cu" "B.Mask" "B.Paste")
			(roundrect_rratio 0.25)
			(net 64 "/X710-AT2 10GbE/OSC_SEL")
			(pintype "passive")
		)
	)
)
